(kicad_pcb
	(version 20260206)
	(generator "pcbnew")
	(generator_version "10.0")
	(general
		(thickness 1.6)
		(legacy_teardrops no)
	)
	(paper "A4")
	(title_block
		(title "04192023_DAF0TMB3IC0_F0TG_MB_C_brd_V02_OCP.brd")
		(comment 1 "Grand Teton / footprints 3092-3097 of 8354")
	)
	(layers
		(0 "F.Cu" signal "TOP")
		(4 "In1.Cu" signal "GND")
		(6 "In2.Cu" signal "IN1")
		(8 "In3.Cu" signal "GND1")
		(10 "In4.Cu" signal "IN2")
		(12 "In5.Cu" signal "GND2")
		(14 "In6.Cu" signal "IN3")
		(16 "In7.Cu" signal "GND3")
		(18 "In8.Cu" signal "VCC")
		(20 "In9.Cu" signal "VCC1")
		(22 "In10.Cu" signal "GND4")
		(24 "In11.Cu" signal "IN4")
		(26 "In12.Cu" signal "GND5")
		(28 "In13.Cu" signal "IN5")
		(30 "In14.Cu" signal "GND6")
		(32 "In15.Cu" signal "IN6")
		(34 "In16.Cu" signal "GND7")
		(2 "B.Cu" signal "BOTTOM")
		(9 "F.Adhes" user "F.Adhesive")
		(11 "B.Adhes" user "B.Adhesive")
		(13 "F.Paste" user "Package Geometry/Pastemask Top")
		(15 "B.Paste" user "Package Geometry/Pastemask Bottom")
		(5 "F.SilkS" user "Ref Des/Silkscreen Top")
		(7 "B.SilkS" user "Ref Des/Silkscreen Bottom")
		(1 "F.Mask" user "Board Geometry/Soldermask Top")
		(3 "B.Mask" user "Board Geometry/Soldermask Bottom")
		(17 "Dwgs.User" user "User.Drawings")
		(19 "Cmts.User" user "User.Comments")
		(21 "Eco1.User" user "User.Eco1")
		(23 "Eco2.User" user "User.Eco2")
		(25 "Edge.Cuts" user "Board Geometry/Outline")
		(27 "Margin" user)
		(31 "F.CrtYd" user "Package Geometry/Place Bound Top")
		(29 "B.CrtYd" user "Package Geometry/Place Bound Bottom")
		(35 "F.Fab" user "Ref Des/Assembly Top")
		(33 "B.Fab" user "Ref Des/Assembly Bottom")
	)
	(footprint ""
		(layer "F.Cu")
		(at 319.405 -194.31)
		(property "Reference" "R423"
			(at 0 0 0)
			(layer "F.SilkS")
			(hide yes)
			(effects
				(font
					(size 1.27 1.27)
				)
			)
		)
		(property "Value" ""
			(at 0 0 0)
			(layer "F.Fab")
			(effects
				(font
					(size 1.27 1.27)
				)
			)
		)
		(duplicate_pad_numbers_are_jumpers no)
		(fp_line
			(start -0.7874 -0.4064)
			(end 0.7874 -0.4064)
			(stroke
				(width 0.1524)
				(type default)
			)
			(layer "F.SilkS")
		)
		(fp_line
			(start -0.7874 0.4064)
			(end -0.7874 -0.4064)
			(stroke
				(width 0.1524)
				(type default)
			)
			(layer "F.SilkS")
		)
		(fp_line
			(start 0.7874 -0.4064)
			(end 0.7874 0.4064)
			(stroke
				(width 0.1524)
				(type default)
			)
			(layer "F.SilkS")
		)
		(fp_line
			(start 0.7874 0.4064)
			(end -0.7874 0.4064)
			(stroke
				(width 0.1524)
				(type default)
			)
			(layer "F.SilkS")
		)
		(fp_line
			(start -0.67945 -0.305054)
			(end -0.12065 -0.305054)
			(stroke
				(width 0.1)
				(type default)
			)
			(layer "F.Fab")
		)
		(fp_line
			(start -0.67945 0.3048)
			(end -0.67945 -0.305054)
			(stroke
				(width 0.1)
				(type default)
			)
			(layer "F.Fab")
		)
		(fp_line
			(start -0.12065 -0.305054)
			(end -0.12065 -0.2794)
			(stroke
				(width 0.1)
				(type default)
			)
			(layer "F.Fab")
		)
		(fp_line
			(start -0.12065 -0.2794)
			(end 0.12065 -0.2794)
			(stroke
				(width 0.1)
				(type default)
			)
			(layer "F.Fab")
		)
		(fp_line
			(start -0.12065 0.2794)
			(end -0.12065 0.3048)
			(stroke
				(width 0.1)
				(type default)
			)
			(layer "F.Fab")
		)
		(fp_line
			(start -0.12065 0.3048)
			(end -0.67945 0.3048)
			(stroke
				(width 0.1)
				(type default)
			)
			(layer "F.Fab")
		)
		(fp_line
			(start 0.120396 0.2794)
			(end -0.12065 0.2794)
			(stroke
				(width 0.1)
				(type default)
			)
			(layer "F.Fab")
		)
		(fp_line
			(start 0.120396 0.3048)
			(end 0.120396 0.2794)
			(stroke
				(width 0.1)
				(type default)
			)
			(layer "F.Fab")
		)
		(fp_line
			(start 0.12065 -0.3048)
			(end 0.67945 -0.3048)
			(stroke
				(width 0.1)
				(type default)
			)
			(layer "F.Fab")
		)
		(fp_line
			(start 0.12065 -0.2794)
			(end 0.12065 -0.3048)
			(stroke
				(width 0.1)
				(type default)
			)
			(layer "F.Fab")
		)
		(fp_line
			(start 0.67945 -0.3048)
			(end 0.67945 0.3048)
			(stroke
				(width 0.1)
				(type default)
			)
			(layer "F.Fab")
		)
		(fp_line
			(start 0.67945 0.3048)
			(end 0.120396 0.3048)
			(stroke
				(width 0.1)
				(type default)
			)
			(layer "F.Fab")
		)
		(pad "1" smd circle
			(at -0.40005 0)
			(size 0 0)
			(layers "F.Cu" "F.Mask" "F.Paste")
			(net "PVDD11_S3_P0")
		)
		(pad "2" smd circle
			(at 0.40005 0)
			(size 0 0)
			(layers "F.Cu" "F.Mask" "F.Paste")
			(net "I3C_0_SPD_DDRAF_CPU0_R_SDA")
		)
	)
	(footprint ""
		(layer "F.Cu")
		(at 21.234654 -35.8013)
		(property "Reference" "R1277"
			(at 0 0 0)
			(layer "F.SilkS")
			(hide yes)
			(effects
				(font
					(size 1.27 1.27)
				)
			)
		)
		(property "Value" ""
			(at 0 0 0)
			(layer "F.Fab")
			(effects
				(font
					(size 1.27 1.27)
				)
			)
		)
		(duplicate_pad_numbers_are_jumpers no)
		(fp_line
			(start -0.7874 -0.4064)
			(end 0.7874 -0.4064)
			(stroke
				(width 0.1524)
				(type default)
			)
			(layer "F.SilkS")
		)
		(fp_line
			(start -0.7874 0.4064)
			(end -0.7874 -0.4064)
			(stroke
				(width 0.1524)
				(type default)
			)
			(layer "F.SilkS")
		)
		(fp_line
			(start 0.7874 -0.4064)
			(end 0.7874 0.4064)
			(stroke
				(width 0.1524)
				(type default)
			)
			(layer "F.SilkS")
		)
		(fp_line
			(start 0.7874 0.4064)
			(end -0.7874 0.4064)
			(stroke
				(width 0.1524)
				(type default)
			)
			(layer "F.SilkS")
		)
		(fp_line
			(start -0.67945 -0.305054)
			(end -0.12065 -0.305054)
			(stroke
				(width 0.1)
				(type default)
			)
			(layer "F.Fab")
		)
		(fp_line
			(start -0.67945 0.3048)
			(end -0.67945 -0.305054)
			(stroke
				(width 0.1)
				(type default)
			)
			(layer "F.Fab")
		)
		(fp_line
			(start -0.12065 -0.305054)
			(end -0.12065 -0.2794)
			(stroke
				(width 0.1)
				(type default)
			)
			(layer "F.Fab")
		)
		(fp_line
			(start -0.12065 -0.2794)
			(end 0.12065 -0.2794)
			(stroke
				(width 0.1)
				(type default)
			)
			(layer "F.Fab")
		)
		(fp_line
			(start -0.12065 0.2794)
			(end -0.12065 0.3048)
			(stroke
				(width 0.1)
				(type default)
			)
			(layer "F.Fab")
		)
		(fp_line
			(start -0.12065 0.3048)
			(end -0.67945 0.3048)
			(stroke
				(width 0.1)
				(type default)
			)
			(layer "F.Fab")
		)
		(fp_line
			(start 0.120396 0.2794)
			(end -0.12065 0.2794)
			(stroke
				(width 0.1)
				(type default)
			)
			(layer "F.Fab")
		)
		(fp_line
			(start 0.120396 0.3048)
			(end 0.120396 0.2794)
			(stroke
				(width 0.1)
				(type default)
			)
			(layer "F.Fab")
		)
		(fp_line
			(start 0.12065 -0.3048)
			(end 0.67945 -0.3048)
			(stroke
				(width 0.1)
				(type default)
			)
			(layer "F.Fab")
		)
		(fp_line
			(start 0.12065 -0.2794)
			(end 0.12065 -0.3048)
			(stroke
				(width 0.1)
				(type default)
			)
			(layer "F.Fab")
		)
		(fp_line
			(start 0.67945 -0.3048)
			(end 0.67945 0.3048)
			(stroke
				(width 0.1)
				(type default)
			)
			(layer "F.Fab")
		)
		(fp_line
			(start 0.67945 0.3048)
			(end 0.120396 0.3048)
			(stroke
				(width 0.1)
				(type default)
			)
			(layer "F.Fab")
		)
		(pad "1" smd circle
			(at -0.40005 0)
			(size 0 0)
			(layers "F.Cu" "F.Mask" "F.Paste")
			(net "SMB_INA230_7_3V3AUX_SDA_R")
		)
		(pad "2" smd circle
			(at 0.40005 0)
			(size 0 0)
			(layers "F.Cu" "F.Mask" "F.Paste")
			(net "SMB_INA230_7_3V3AUX_SDA_R1")
		)
	)
	(footprint ""
		(layer "F.Cu")
		(at 315.771022 -36.890706)
		(property "Reference" "R2900"
			(at 0 0 0)
			(layer "F.SilkS")
			(hide yes)
			(effects
				(font
					(size 1.27 1.27)
				)
			)
		)
		(property "Value" ""
			(at 0 0 0)
			(layer "F.Fab")
			(effects
				(font
					(size 1.27 1.27)
				)
			)
		)
		(duplicate_pad_numbers_are_jumpers no)
		(fp_line
			(start -0.7874 -0.4064)
			(end 0.7874 -0.4064)
			(stroke
				(width 0.1524)
				(type default)
			)
			(layer "F.SilkS")
		)
		(fp_line
			(start -0.7874 0.4064)
			(end -0.7874 -0.4064)
			(stroke
				(width 0.1524)
				(type default)
			)
			(layer "F.SilkS")
		)
		(fp_line
			(start 0.7874 -0.4064)
			(end 0.7874 0.4064)
			(stroke
				(width 0.1524)
				(type default)
			)
			(layer "F.SilkS")
		)
		(fp_line
			(start 0.7874 0.4064)
			(end -0.7874 0.4064)
			(stroke
				(width 0.1524)
				(type default)
			)
			(layer "F.SilkS")
		)
		(fp_line
			(start -0.67945 -0.305054)
			(end -0.12065 -0.305054)
			(stroke
				(width 0.1)
				(type default)
			)
			(layer "F.Fab")
		)
		(fp_line
			(start -0.67945 0.3048)
			(end -0.67945 -0.305054)
			(stroke
				(width 0.1)
				(type default)
			)
			(layer "F.Fab")
		)
		(fp_line
			(start -0.12065 -0.305054)
			(end -0.12065 -0.2794)
			(stroke
				(width 0.1)
				(type default)
			)
			(layer "F.Fab")
		)
		(fp_line
			(start -0.12065 -0.2794)
			(end 0.12065 -0.2794)
			(stroke
				(width 0.1)
				(type default)
			)
			(layer "F.Fab")
		)
		(fp_line
			(start -0.12065 0.2794)
			(end -0.12065 0.3048)
			(stroke
				(width 0.1)
				(type default)
			)
			(layer "F.Fab")
		)
		(fp_line
			(start -0.12065 0.3048)
			(end -0.67945 0.3048)
			(stroke
				(width 0.1)
				(type default)
			)
			(layer "F.Fab")
		)
		(fp_line
			(start 0.120396 0.2794)
			(end -0.12065 0.2794)
			(stroke
				(width 0.1)
				(type default)
			)
			(layer "F.Fab")
		)
		(fp_line
			(start 0.120396 0.3048)
			(end 0.120396 0.2794)
			(stroke
				(width 0.1)
				(type default)
			)
			(layer "F.Fab")
		)
		(fp_line
			(start 0.12065 -0.3048)
			(end 0.67945 -0.3048)
			(stroke
				(width 0.1)
				(type default)
			)
			(layer "F.Fab")
		)
		(fp_line
			(start 0.12065 -0.2794)
			(end 0.12065 -0.3048)
			(stroke
				(width 0.1)
				(type default)
			)
			(layer "F.Fab")
		)
		(fp_line
			(start 0.67945 -0.3048)
			(end 0.67945 0.3048)
			(stroke
				(width 0.1)
				(type default)
			)
			(layer "F.Fab")
		)
		(fp_line
			(start 0.67945 0.3048)
			(end 0.120396 0.3048)
			(stroke
				(width 0.1)
				(type default)
			)
			(layer "F.Fab")
		)
		(pad "1" smd circle
			(at -0.40005 0)
			(size 0 0)
			(layers "F.Cu" "F.Mask" "F.Paste")
			(net "MAX11617_VREF")
		)
		(pad "2" smd circle
			(at 0.40005 0)
			(size 0 0)
			(layers "F.Cu" "F.Mask" "F.Paste")
			(net "MAX11617_VREF_R")
		)
	)
	(footprint ""
		(layer "F.Cu")
		(at 416.43046 -358.241092)
		(property "Reference" "PC194"
			(at 0 0 0)
			(layer "F.SilkS")
			(hide yes)
			(effects
				(font
					(size 1.27 1.27)
				)
			)
		)
		(property "Value" ""
			(at 0 0 0)
			(layer "F.Fab")
			(effects
				(font
					(size 1.27 1.27)
				)
			)
		)
		(duplicate_pad_numbers_are_jumpers no)
		(fp_line
			(start -0.7874 -0.4064)
			(end 0.7874 -0.4064)
			(stroke
				(width 0.1524)
				(type default)
			)
			(layer "F.SilkS")
		)
		(fp_line
			(start -0.7874 0.4064)
			(end -0.7874 -0.4064)
			(stroke
				(width 0.1524)
				(type default)
			)
			(layer "F.SilkS")
		)
		(fp_line
			(start 0.7874 -0.4064)
			(end 0.7874 0.4064)
			(stroke
				(width 0.1524)
				(type default)
			)
			(layer "F.SilkS")
		)
		(fp_line
			(start 0.7874 0.4064)
			(end -0.7874 0.4064)
			(stroke
				(width 0.1524)
				(type default)
			)
			(layer "F.SilkS")
		)
		(fp_line
			(start -0.67945 -0.305054)
			(end -0.12065 -0.305054)
			(stroke
				(width 0.1)
				(type default)
			)
			(layer "F.Fab")
		)
		(fp_line
			(start -0.67945 0.3048)
			(end -0.67945 -0.305054)
			(stroke
				(width 0.1)
				(type default)
			)
			(layer "F.Fab")
		)
		(fp_line
			(start -0.12065 -0.305054)
			(end -0.12065 -0.2794)
			(stroke
				(width 0.1)
				(type default)
			)
			(layer "F.Fab")
		)
		(fp_line
			(start -0.12065 -0.2794)
			(end 0.12065 -0.2794)
			(stroke
				(width 0.1)
				(type default)
			)
			(layer "F.Fab")
		)
		(fp_line
			(start -0.12065 0.2794)
			(end -0.12065 0.3048)
			(stroke
				(width 0.1)
				(type default)
			)
			(layer "F.Fab")
		)
		(fp_line
			(start -0.12065 0.3048)
			(end -0.67945 0.3048)
			(stroke
				(width 0.1)
				(type default)
			)
			(layer "F.Fab")
		)
		(fp_line
			(start 0.120396 0.2794)
			(end -0.12065 0.2794)
			(stroke
				(width 0.1)
				(type default)
			)
			(layer "F.Fab")
		)
		(fp_line
			(start 0.120396 0.3048)
			(end 0.120396 0.2794)
			(stroke
				(width 0.1)
				(type default)
			)
			(layer "F.Fab")
		)
		(fp_line
			(start 0.12065 -0.3048)
			(end 0.67945 -0.3048)
			(stroke
				(width 0.1)
				(type default)
			)
			(layer "F.Fab")
		)
		(fp_line
			(start 0.12065 -0.2794)
			(end 0.12065 -0.3048)
			(stroke
				(width 0.1)
				(type default)
			)
			(layer "F.Fab")
		)
		(fp_line
			(start 0.67945 -0.3048)
			(end 0.67945 0.3048)
			(stroke
				(width 0.1)
				(type default)
			)
			(layer "F.Fab")
		)
		(fp_line
			(start 0.67945 0.3048)
			(end 0.120396 0.3048)
			(stroke
				(width 0.1)
				(type default)
			)
			(layer "F.Fab")
		)
		(pad "1" smd circle
			(at -0.40005 0)
			(size 0 0)
			(layers "F.Cu" "F.Mask" "F.Paste")
			(net "VSENSE_PVDD11_S3_P0_R")
		)
		(pad "2" smd circle
			(at 0.40005 0)
			(size 0 0)
			(layers "F.Cu" "F.Mask" "F.Paste")
			(net "VSENSE_VSS_SENSE_C_P0")
		)
	)
	(footprint ""
		(layer "F.Cu")
		(at 157.686502 -348.280228 180)
		(property "Reference" "PR392"
			(at 0 0 180)
			(layer "F.SilkS")
			(hide yes)
			(effects
				(font
					(size 1.27 1.27)
				)
			)
		)
		(property "Value" ""
			(at 0 0 180)
			(layer "F.Fab")
			(effects
				(font
					(size 1.27 1.27)
				)
			)
		)
		(duplicate_pad_numbers_are_jumpers no)
		(fp_line
			(start 0.7874 0.4064)
			(end -0.7874 0.4064)
			(stroke
				(width 0.1524)
				(type default)
			)
			(layer "F.SilkS")
		)
		(fp_line
			(start 0.7874 -0.4064)
			(end 0.7874 0.4064)
			(stroke
				(width 0.1524)
				(type default)
			)
			(layer "F.SilkS")
		)
		(fp_line
			(start -0.7874 0.4064)
			(end -0.7874 -0.4064)
			(stroke
				(width 0.1524)
				(type default)
			)
			(layer "F.SilkS")
		)
		(fp_line
			(start -0.7874 -0.4064)
			(end 0.7874 -0.4064)
			(stroke
				(width 0.1524)
				(type default)
			)
			(layer "F.SilkS")
		)
		(fp_line
			(start 0.67945 0.3048)
			(end 0.120396 0.3048)
			(stroke
				(width 0.1)
				(type default)
			)
			(layer "F.Fab")
		)
		(fp_line
			(start 0.67945 -0.3048)
			(end 0.67945 0.3048)
			(stroke
				(width 0.1)
				(type default)
			)
			(layer "F.Fab")
		)
		(fp_line
			(start 0.12065 -0.2794)
			(end 0.12065 -0.3048)
			(stroke
				(width 0.1)
				(type default)
			)
			(layer "F.Fab")
		)
		(fp_line
			(start 0.12065 -0.3048)
			(end 0.67945 -0.3048)
			(stroke
				(width 0.1)
				(type default)
			)
			(layer "F.Fab")
		)
		(fp_line
			(start 0.120396 0.3048)
			(end 0.120396 0.2794)
			(stroke
				(width 0.1)
				(type default)
			)
			(layer "F.Fab")
		)
		(fp_line
			(start 0.120396 0.2794)
			(end -0.12065 0.2794)
			(stroke
				(width 0.1)
				(type default)
			)
			(layer "F.Fab")
		)
		(fp_line
			(start -0.12065 0.3048)
			(end -0.67945 0.3048)
			(stroke
				(width 0.1)
				(type default)
			)
			(layer "F.Fab")
		)
		(fp_line
			(start -0.12065 0.2794)
			(end -0.12065 0.3048)
			(stroke
				(width 0.1)
				(type default)
			)
			(layer "F.Fab")
		)
		(fp_line
			(start -0.12065 -0.2794)
			(end 0.12065 -0.2794)
			(stroke
				(width 0.1)
				(type default)
			)
			(layer "F.Fab")
		)
		(fp_line
			(start -0.12065 -0.305054)
			(end -0.12065 -0.2794)
			(stroke
				(width 0.1)
				(type default)
			)
			(layer "F.Fab")
		)
		(fp_line
			(start -0.67945 0.3048)
			(end -0.67945 -0.305054)
			(stroke
				(width 0.1)
				(type default)
			)
			(layer "F.Fab")
		)
		(fp_line
			(start -0.67945 -0.305054)
			(end -0.12065 -0.305054)
			(stroke
				(width 0.1)
				(type default)
			)
			(layer "F.Fab")
		)
		(pad "1" smd circle
			(at -0.40005 0 180)
			(size 0 0)
			(layers "F.Cu" "F.Mask" "F.Paste")
			(net "PVDD11_S3_P1_RESET_N_R")
		)
		(pad "2" smd circle
			(at 0.40005 0 180)
			(size 0 0)
			(layers "F.Cu" "F.Mask" "F.Paste")
			(net "PVDD11_S3_P1_RESET_N")
		)
	)
	(footprint ""
		(layer "F.Cu")
		(at 329.223624 -141.591792 90)
		(property "Reference" "PR435"
			(at 0 0 90)
			(layer "F.SilkS")
			(hide yes)
			(effects
				(font
					(size 1.27 1.27)
				)
			)
		)
		(property "Value" ""
			(at 0 0 90)
			(layer "F.Fab")
			(effects
				(font
					(size 1.27 1.27)
				)
			)
		)
		(duplicate_pad_numbers_are_jumpers no)
		(fp_line
			(start 0.7874 -0.4064)
			(end 0.7874 0.4064)
			(stroke
				(width 0.1524)
				(type default)
			)
			(layer "F.SilkS")
		)
		(fp_line
			(start -0.7874 -0.4064)
			(end 0.7874 -0.4064)
			(stroke
				(width 0.1524)
				(type default)
			)
			(layer "F.SilkS")
		)
		(fp_line
			(start 0.7874 0.4064)
			(end -0.7874 0.4064)
			(stroke
				(width 0.1524)
				(type default)
			)
			(layer "F.SilkS")
		)
		(fp_line
			(start -0.7874 0.4064)
			(end -0.7874 -0.4064)
			(stroke
				(width 0.1524)
				(type default)
			)
			(layer "F.SilkS")
		)
		(fp_line
			(start -0.12065 -0.305054)
			(end -0.12065 -0.2794)
			(stroke
				(width 0.1)
				(type default)
			)
			(layer "F.Fab")
		)
		(fp_line
			(start -0.67945 -0.305054)
			(end -0.12065 -0.305054)
			(stroke
				(width 0.1)
				(type default)
			)
			(layer "F.Fab")
		)
		(fp_line
			(start 0.67945 -0.3048)
			(end 0.67945 0.3048)
			(stroke
				(width 0.1)
				(type default)
			)
			(layer "F.Fab")
		)
		(fp_line
			(start 0.12065 -0.3048)
			(end 0.67945 -0.3048)
			(stroke
				(width 0.1)
				(type default)
			)
			(layer "F.Fab")
		)
		(fp_line
			(start 0.12065 -0.2794)
			(end 0.12065 -0.3048)
			(stroke
				(width 0.1)
				(type default)
			)
			(layer "F.Fab")
		)
		(fp_line
			(start -0.12065 -0.2794)
			(end 0.12065 -0.2794)
			(stroke
				(width 0.1)
				(type default)
			)
			(layer "F.Fab")
		)
		(fp_line
			(start 0.120396 0.2794)
			(end -0.12065 0.2794)
			(stroke
				(width 0.1)
				(type default)
			)
			(layer "F.Fab")
		)
		(fp_line
			(start -0.12065 0.2794)
			(end -0.12065 0.3048)
			(stroke
				(width 0.1)
				(type default)
			)
			(layer "F.Fab")
		)
		(fp_line
			(start 0.67945 0.3048)
			(end 0.120396 0.3048)
			(stroke
				(width 0.1)
				(type default)
			)
			(layer "F.Fab")
		)
		(fp_line
			(start 0.120396 0.3048)
			(end 0.120396 0.2794)
			(stroke
				(width 0.1)
				(type default)
			)
			(layer "F.Fab")
		)
		(fp_line
			(start -0.12065 0.3048)
			(end -0.67945 0.3048)
			(stroke
				(width 0.1)
				(type default)
			)
			(layer "F.Fab")
		)
		(fp_line
			(start -0.67945 0.3048)
			(end -0.67945 -0.305054)
			(stroke
				(width 0.1)
				(type default)
			)
			(layer "F.Fab")
		)
		(pad "1" smd circle
			(at -0.40005 0 90)
			(size 0 0)
			(layers "F.Cu" "F.Mask" "F.Paste")
			(net "PVDD18_S5_P0_RGND")
		)
		(pad "2" smd circle
			(at 0.40005 0 90)
			(size 0 0)
			(layers "F.Cu" "F.Mask" "F.Paste")
			(net "VSENSE_PVDD18_S5_P0_DN")
		)
	)
)
